(kicad_pcb
	(version 20241229)
	(generator "pcbnew")
	(generator_version "9.0")
	(general
		(thickness 1.294)
		(legacy_teardrops no)
	)
	(paper "A3")
	(title_block
		(title "Kintex 410T devboard")
		(date "2024-04-03")
		(rev "1.1.2")
		(comment 9 "footprints 557-561 of 975")
	)
	(layers
		(0 "F.Cu" mixed)
		(4 "In1.Cu" power)
		(6 "In2.Cu" power)
		(8 "In3.Cu" mixed)
		(10 "In4.Cu" power)
		(12 "In5.Cu" mixed)
		(14 "In6.Cu" power)
		(16 "In7.Cu" mixed)
		(18 "In8.Cu" power)
		(2 "B.Cu" mixed)
		(9 "F.Adhes" user "F.Adhesive")
		(11 "B.Adhes" user "B.Adhesive")
		(13 "F.Paste" user)
		(15 "B.Paste" user)
		(5 "F.SilkS" user "F.Silkscreen")
		(7 "B.SilkS" user "B.Silkscreen")
		(1 "F.Mask" user)
		(3 "B.Mask" user)
		(17 "Dwgs.User" user "User.Drawings")
		(19 "Cmts.User" user "User.Comments")
		(21 "Eco1.User" user "User.Eco1")
		(23 "Eco2.User" user "User.Eco2")
		(25 "Edge.Cuts" user)
		(27 "Margin" user)
		(31 "F.CrtYd" user "F.Courtyard")
		(29 "B.CrtYd" user "B.Courtyard")
		(35 "F.Fab" user)
		(33 "B.Fab" user)
	)
	(footprint "antmicro-footprints:R_0402_1005Metric"
		(layer "B.Cu")
		(at 251.101 179.05 90)
		(descr "Resistor SMD 0402")
		(tags "resistor SMD 0402")
		(property "Reference" "R53"
			(at -0.775 0.374 270)
			(layer "B.SilkS")
			(effects
				(font
					(size 0.7 0.7)
					(thickness 0.15)
				)
				(justify left bottom mirror)
			)
		)
		(property "Value" "R_1k2_0402"
			(at 0 -1.4 270)
			(layer "B.Fab")
			(effects
				(font
					(size 0.7 0.7)
					(thickness 0.15)
				)
				(justify left bottom mirror)
			)
		)
		(property "Description" "SMD Chip Resistor, 1.2 kohm, ± 1%, 62.5 mW, 0402 [1005 Metric], Thick Film, General Purpose"
			(at 0 0 90)
			(layer "F.Fab")
			(hide yes)
			(effects
				(font
					(size 1.27 1.27)
					(thickness 0.15)
				)
			)
		)
		(property "Author" "Antmicro"
			(at 430.151 -72.051 0)
			(layer "B.Fab")
			(hide yes)
			(effects
				(font
					(size 1 1)
					(thickness 0.15)
				)
				(justify mirror)
			)
		)
		(property "License" "Apache-2.0"
			(at 430.151 -72.051 0)
			(layer "B.Fab")
			(hide yes)
			(effects
				(font
					(size 1 1)
					(thickness 0.15)
				)
				(justify mirror)
			)
		)
		(property "MPN" "CR0402-FX-1201GLF"
			(at 430.151 -72.051 0)
			(layer "B.Fab")
			(hide yes)
			(effects
				(font
					(size 1 1)
					(thickness 0.15)
				)
				(justify mirror)
			)
		)
		(property "Manufacturer" "Bourns"
			(at 430.151 -72.051 0)
			(layer "B.Fab")
			(hide yes)
			(effects
				(font
					(size 1 1)
					(thickness 0.15)
				)
				(justify mirror)
			)
		)
		(property "Tolerance" "1%"
			(at 430.151 -72.051 0)
			(layer "B.Fab")
			(hide yes)
			(effects
				(font
					(size 1 1)
					(thickness 0.15)
				)
				(justify mirror)
			)
		)
		(property "Val" "1k2"
			(at 430.151 -72.051 0)
			(layer "B.Fab")
			(hide yes)
			(effects
				(font
					(size 1 1)
					(thickness 0.15)
				)
				(justify mirror)
			)
		)
		(sheetname "Power supply")
		(sheetfile "power-supply.kicad_sch")
		(attr smd)
		(fp_rect
			(start -0.925 0.47)
			(end 0.925 -0.47)
			(stroke
				(width 0.05)
				(type default)
			)
			(fill no)
			(layer "B.CrtYd")
		)
		(fp_rect
			(start -0.5 0.25)
			(end 0.5 -0.25)
			(stroke
				(width 0.15)
				(type solid)
			)
			(fill no)
			(layer "B.Fab")
		)
		(pad "1" smd roundrect
			(at -0.48 0 90)
			(size 0.59 0.64)
			(layers "B.Cu" "B.Mask" "B.Paste")
			(roundrect_rratio 0.25)
			(net 697 "/Power supply/VSS")
			(pintype "passive")
		)
		(pad "2" smd roundrect
			(at 0.48 0 90)
			(size 0.59 0.64)
			(layers "B.Cu" "B.Mask" "B.Paste")
			(roundrect_rratio 0.25)
			(net 886 "/Power supply/CLSB")
			(pintype "passive")
		)
	)
	(footprint "antmicro-footprints:R_Array_4x0201_Panasonic_EXB18V"
		(layer "B.Cu")
		(at 259.195 73.4 180)
		(property "Reference" "R133"
			(at 1.295 0.75 0)
			(layer "B.SilkS")
			(effects
				(font
					(size 0.7 0.7)
					(thickness 0.15)
				)
				(justify right bottom mirror)
			)
		)
		(property "Value" "4x10k_0201_array"
			(at -1.1 -1.8 0)
			(layer "B.Fab")
			(effects
				(font
					(size 0.7 0.7)
					(thickness 0.15)
				)
				(justify left bottom mirror)
			)
		)
		(property "Description" "Fixed Network Resistor, 10 kohm, Isolated, 4 Resistors, 0502 [1406 Metric], Flat, ± 5%"
			(at 0 0 180)
			(layer "F.Fab")
			(hide yes)
			(effects
				(font
					(size 1.27 1.27)
					(thickness 0.15)
				)
			)
		)
		(property "Author" "Antmicro"
			(at 518.39 146.8 0)
			(layer "B.Fab")
			(hide yes)
			(effects
				(font
					(size 1 1)
					(thickness 0.15)
				)
				(justify mirror)
			)
		)
		(property "License" "Apache-2.0"
			(at 518.39 146.8 0)
			(layer "B.Fab")
			(hide yes)
			(effects
				(font
					(size 1 1)
					(thickness 0.15)
				)
				(justify mirror)
			)
		)
		(property "MPN" "EXB-18V103JX"
			(at 518.39 146.8 0)
			(layer "B.Fab")
			(hide yes)
			(effects
				(font
					(size 1 1)
					(thickness 0.15)
				)
				(justify mirror)
			)
		)
		(property "Manufacturer" "Panasonic"
			(at 518.39 146.8 0)
			(layer "B.Fab")
			(hide yes)
			(effects
				(font
					(size 1 1)
					(thickness 0.15)
				)
				(justify mirror)
			)
		)
		(property "Val" "4x10k_0201"
			(at 518.39 146.8 0)
			(layer "B.Fab")
			(hide yes)
			(effects
				(font
					(size 1 1)
					(thickness 0.15)
				)
				(justify mirror)
			)
		)
		(sheetname "User GPIO + LED + button + DIP switch")
		(sheetfile "user-gpio.kicad_sch")
		(attr smd)
		(fp_line
			(start 0.8 0.45)
			(end 0.8 -0.45)
			(stroke
				(width 0.12)
				(type solid)
			)
			(layer "B.SilkS")
		)
		(fp_line
			(start -0.8 0.45)
			(end -0.8 -0.45)
			(stroke
				(width 0.12)
				(type solid)
			)
			(layer "B.SilkS")
		)
		(fp_rect
			(start -0.898 0.66)
			(end 0.898 -0.65)
			(stroke
				(width 0.05)
				(type solid)
			)
			(fill no)
			(layer "B.CrtYd")
		)
		(pad "1" smd roundrect
			(at -0.6 -0.298 180)
			(size 0.2 0.4)
			(layers "B.Cu" "B.Mask" "B.Paste")
			(roundrect_rratio 0.25)
			(net 1318 "/USER_IO.DIP_SW7")
			(pinfunction "R1.1")
			(pintype "passive")
		)
		(pad "2" smd roundrect
			(at -0.202 -0.298 180)
			(size 0.2 0.4)
			(layers "B.Cu" "B.Mask" "B.Paste")
			(roundrect_rratio 0.25)
			(net 1320 "/USER_IO.DIP_SW6")
			(pinfunction "R2.1")
			(pintype "passive")
		)
		(pad "3" smd roundrect
			(at 0.2 -0.298 180)
			(size 0.2 0.4)
			(layers "B.Cu" "B.Mask" "B.Paste")
			(roundrect_rratio 0.25)
			(net 1322 "/USER_IO.DIP_SW5")
			(pinfunction "R3.1")
			(pintype "passive")
		)
		(pad "4" smd roundrect
			(at 0.598 -0.298 180)
			(size 0.2 0.4)
			(layers "B.Cu" "B.Mask" "B.Paste")
			(roundrect_rratio 0.25)
			(net 1324 "/USER_IO.DIP_SW4")
			(pinfunction "R4.1")
			(pintype "passive")
		)
		(pad "5" smd roundrect
			(at 0.598 0.3 180)
			(size 0.2 0.4)
			(layers "B.Cu" "B.Mask" "B.Paste")
			(roundrect_rratio 0.25)
			(net 26 "+1V8")
			(pinfunction "R4.2")
			(pintype "passive")
		)
		(pad "6" smd roundrect
			(at 0.2 0.3 180)
			(size 0.2 0.4)
			(layers "B.Cu" "B.Mask" "B.Paste")
			(roundrect_rratio 0.25)
			(net 26 "+1V8")
			(pinfunction "R3.2")
			(pintype "passive")
		)
		(pad "7" smd roundrect
			(at -0.202 0.3 180)
			(size 0.2 0.4)
			(layers "B.Cu" "B.Mask" "B.Paste")
			(roundrect_rratio 0.25)
			(net 26 "+1V8")
			(pinfunction "R2.2")
			(pintype "passive")
		)
		(pad "8" smd roundrect
			(at -0.6 0.3 180)
			(size 0.2 0.4)
			(layers "B.Cu" "B.Mask" "B.Paste")
			(roundrect_rratio 0.25)
			(net 26 "+1V8")
			(pinfunction "R1.2")
			(pintype "passive")
		)
	)
	(footprint "antmicro-footprints:C_0603_1608Metric"
		(layer "B.Cu")
		(at 200.6 121.25)
		(descr "Capacitor SMD 0603")
		(tags "capacitor 0603")
		(property "Reference" "C105"
			(at 27.175 -29.65 180)
			(layer "B.SilkS")
			(effects
				(font
					(size 0.7 0.7)
					(thickness 0.15)
				)
				(justify left bottom mirror)
			)
		)
		(property "Value" "C_47u_0603"
			(at 0 -1.6 180)
			(layer "B.Fab")
			(effects
				(font
					(size 0.7 0.7)
					(thickness 0.15)
				)
				(justify left bottom mirror)
			)
		)
		(property "Description" "SMD Multilayer Ceramic Capacitor, 47 µF, 6.3 V, 0603 [1608 Metric], ± 20%, X5R, GRM Series"
			(at 0 0 0)
			(layer "F.Fab")
			(hide yes)
			(effects
				(font
					(size 1.27 1.27)
					(thickness 0.15)
				)
			)
		)
		(property "Author" "Antmicro"
			(at 0 0 0)
			(layer "B.Fab")
			(hide yes)
			(effects
				(font
					(size 1 1)
					(thickness 0.15)
				)
				(justify mirror)
			)
		)
		(property "Dielectric" ""
			(at 0 0 0)
			(layer "B.Fab")
			(hide yes)
			(effects
				(font
					(size 1 1)
					(thickness 0.15)
				)
				(justify mirror)
			)
		)
		(property "License" "Apache-2.0"
			(at 0 0 0)
			(layer "B.Fab")
			(hide yes)
			(effects
				(font
					(size 1 1)
					(thickness 0.15)
				)
				(justify mirror)
			)
		)
		(property "MPN" "GRM188R60J476ME15D"
			(at 0 0 0)
			(layer "B.Fab")
			(hide yes)
			(effects
				(font
					(size 1 1)
					(thickness 0.15)
				)
				(justify mirror)
			)
		)
		(property "Manufacturer" "Murata"
			(at 0 0 0)
			(layer "B.Fab")
			(hide yes)
			(effects
				(font
					(size 1 1)
					(thickness 0.15)
				)
				(justify mirror)
			)
		)
		(property "Val" "47u"
			(at 0 0 0)
			(layer "B.Fab")
			(hide yes)
			(effects
				(font
					(size 1 1)
					(thickness 0.15)
				)
				(justify mirror)
			)
		)
		(property "Voltage" ""
			(at 0 0 0)
			(layer "B.Fab")
			(hide yes)
			(effects
				(font
					(size 1 1)
					(thickness 0.15)
				)
				(justify mirror)
			)
		)
		(sheetname "FPGA Bank 16 & 17")
		(sheetfile "fpga-bank-16-17.kicad_sch")
		(attr smd)
		(fp_line
			(start -0.15 -0.4)
			(end 0.15 -0.4)
			(stroke
				(width 0.15)
				(type solid)
			)
			(layer "B.SilkS")
		)
		(fp_line
			(start -0.15 0.4)
			(end 0.15 0.4)
			(stroke
				(width 0.15)
				(type solid)
			)
			(layer "B.SilkS")
		)
		(fp_rect
			(start -1.25 0.65)
			(end 1.25 -0.65)
			(stroke
				(width 0.05)
				(type solid)
			)
			(fill no)
			(layer "B.CrtYd")
		)
		(fp_rect
			(start -0.8 0.4)
			(end 0.8 -0.4)
			(stroke
				(width 0.15)
				(type solid)
			)
			(fill no)
			(layer "B.Fab")
		)
		(pad "1" smd roundrect
			(at -0.7 0)
			(size 0.8 1)
			(layers "B.Cu" "B.Mask" "B.Paste")
			(roundrect_rratio 0.2)
			(net 24 "+3V3")
			(pintype "passive")
		)
		(pad "2" smd roundrect
			(at 0.7 0)
			(size 0.8 1)
			(layers "B.Cu" "B.Mask" "B.Paste")
			(roundrect_rratio 0.2)
			(net 1 "GND")
			(pintype "passive")
		)
	)
	(footprint "antmicro-footprints:R_0402_1005Metric"
		(layer "B.Cu")
		(at 220.6 125.8)
		(descr "Resistor SMD 0402")
		(tags "resistor SMD 0402")
		(property "Reference" "R105"
			(at 1.325 -2.5 180)
			(layer "B.SilkS")
			(effects
				(font
					(size 0.7 0.7)
					(thickness 0.15)
				)
				(justify left bottom mirror)
			)
		)
		(property "Value" "R_0R_0402"
			(at 0 -1.4 180)
			(layer "B.Fab")
			(effects
				(font
					(size 0.7 0.7)
					(thickness 0.15)
				)
				(justify left bottom mirror)
			)
		)
		(property "Description" "SMD Chip Resistor, Jumper, 0 ohm, 100 mW, 0402 [1005 Metric], Thick Film, General Purpose"
			(at 0 0 0)
			(layer "F.Fab")
			(hide yes)
			(effects
				(font
					(size 1.27 1.27)
					(thickness 0.15)
				)
			)
		)
		(property "Author" "Antmicro"
			(at 0 0 0)
			(layer "B.Fab")
			(hide yes)
			(effects
				(font
					(size 1 1)
					(thickness 0.15)
				)
				(justify mirror)
			)
		)
		(property "Current" "1A"
			(at 0 0 0)
			(layer "B.Fab")
			(hide yes)
			(effects
				(font
					(size 1 1)
					(thickness 0.15)
				)
				(justify mirror)
			)
		)
		(property "License" "Apache-2.0"
			(at 0 0 0)
			(layer "B.Fab")
			(hide yes)
			(effects
				(font
					(size 1 1)
					(thickness 0.15)
				)
				(justify mirror)
			)
		)
		(property "MPN" "ERJ2GE0R00X"
			(at 0 0 0)
			(layer "B.Fab")
			(hide yes)
			(effects
				(font
					(size 1 1)
					(thickness 0.15)
				)
				(justify mirror)
			)
		)
		(property "Manufacturer" "Panasonic"
			(at 0 0 0)
			(layer "B.Fab")
			(hide yes)
			(effects
				(font
					(size 1 1)
					(thickness 0.15)
				)
				(justify mirror)
			)
		)
		(property "Tolerance" ""
			(at 0 0 0)
			(layer "B.Fab")
			(hide yes)
			(effects
				(font
					(size 1 1)
					(thickness 0.15)
				)
				(justify mirror)
			)
		)
		(property "Val" "0R"
			(at 0 0 0)
			(layer "B.Fab")
			(hide yes)
			(effects
				(font
					(size 1 1)
					(thickness 0.15)
				)
				(justify mirror)
			)
		)
		(sheetname "User GPIO + LED + button + DIP switch")
		(sheetfile "user-gpio.kicad_sch")
		(attr smd)
		(fp_rect
			(start -0.925 0.47)
			(end 0.925 -0.47)
			(stroke
				(width 0.05)
				(type default)
			)
			(fill no)
			(layer "B.CrtYd")
		)
		(fp_rect
			(start -0.5 0.25)
			(end 0.5 -0.25)
			(stroke
				(width 0.15)
				(type solid)
			)
			(fill no)
			(layer "B.Fab")
		)
		(pad "1" smd roundrect
			(at -0.48 0)
			(size 0.59 0.64)
			(layers "B.Cu" "B.Mask" "B.Paste")
			(roundrect_rratio 0.25)
			(net 432 "/FPGA Bank 12 & 13/FAN_PWM_CTRL")
			(pintype "passive")
		)
		(pad "2" smd roundrect
			(at 0.48 0)
			(size 0.59 0.64)
			(layers "B.Cu" "B.Mask" "B.Paste")
			(roundrect_rratio 0.25)
			(net 876 "/User GPIO + LED + button + DIP switch/FAN_PWM_CTRL_AON")
			(pintype "passive")
		)
	)
	(footprint "antmicro-footprints:C_0201"
		(layer "B.Cu")
		(at 191.2 124.2 -45)
		(descr "Capacitor SMD 0201")
		(tags "capacitor SMD 0201")
		(property "Reference" "C80"
			(at -4.507806 -35.797281 315)
			(unlocked yes)
			(layer "B.SilkS")
			(effects
				(font
					(size 0.7 0.7)
					(thickness 0.15)
				)
				(justify left bottom mirror)
			)
		)
		(property "Value" "C_4u7_0201"
			(at 0 -1.399999 135)
			(layer "B.Fab")
			(effects
				(font
					(size 0.7 0.7)
					(thickness 0.15)
				)
				(justify left bottom mirror)
			)
		)
		(property "Description" "SMD Multilayer Ceramic Capacitor, 4.7 µF, 6.3 V, 0201 [0603 Metric], ± 20%, X5R, GRM Series"
			(at 0 0 315)
			(layer "F.Fab")
			(hide yes)
			(effects
				(font
					(size 1.27 1.27)
					(thickness 0.15)
				)
			)
		)
		(property "Author" "Antmicro"
			(at -31.821479 171.576155 0)
			(layer "B.Fab")
			(hide yes)
			(effects
				(font
					(size 1 1)
					(thickness 0.15)
				)
				(justify mirror)
			)
		)
		(property "Dielectric" ""
			(at -31.821479 171.576155 0)
			(layer "B.Fab")
			(hide yes)
			(effects
				(font
					(size 1 1)
					(thickness 0.15)
				)
				(justify mirror)
			)
		)
		(property "License" "Apache-2.0"
			(at -31.821479 171.576155 0)
			(layer "B.Fab")
			(hide yes)
			(effects
				(font
					(size 1 1)
					(thickness 0.15)
				)
				(justify mirror)
			)
		)
		(property "MPN" "GRM035R60J475ME15D"
			(at -31.821479 171.576155 0)
			(layer "B.Fab")
			(hide yes)
			(effects
				(font
					(size 1 1)
					(thickness 0.15)
				)
				(justify mirror)
			)
		)
		(property "Manufacturer" "Murata"
			(at -31.821479 171.576155 0)
			(layer "B.Fab")
			(hide yes)
			(effects
				(font
					(size 1 1)
					(thickness 0.15)
				)
				(justify mirror)
			)
		)
		(property "Val" "4u7"
			(at -31.821479 171.576155 0)
			(layer "B.Fab")
			(hide yes)
			(effects
				(font
					(size 1 1)
					(thickness 0.15)
				)
				(justify mirror)
			)
		)
		(property "Voltage" ""
			(at -31.821479 171.576155 0)
			(layer "B.Fab")
			(hide yes)
			(effects
				(font
					(size 1 1)
					(thickness 0.15)
				)
				(justify mirror)
			)
		)
		(sheetname "FPGA supply")
		(sheetfile "fpga-supply.kicad_sch")
		(attr smd)
		(fp_poly
			(pts
				(xy -0.7 0.35) (xy 0.7 0.35) (xy 0.7 -0.35) (xy -0.7 -0.35)
			)
			(stroke
				(width 0.05)
				(type default)
			)
			(fill no)
			(layer "B.CrtYd")
		)
		(fp_poly
			(pts
				(xy 0.3 -0.15) (xy -0.301 -0.15) (xy -0.301 0.149) (xy 0.3 0.149)
			)
			(stroke
				(width 0.15)
				(type solid)
			)
			(fill no)
			(layer "B.Fab")
		)
		(pad "" smd roundrect
			(at -0.349 0.002 315)
			(size 0.318 0.36)
			(layers "B.Paste")
			(roundrect_rratio 0.25)
		)
		(pad "" smd roundrect
			(at 0.341 0.002 315)
			(size 0.318 0.36)
			(layers "B.Paste")
			(roundrect_rratio 0.25)
		)
		(pad "1" smd roundrect
			(at -0.321 0.002 315)
			(size 0.46 0.4)
			(layers "B.Cu" "B.Mask")
			(roundrect_rratio 0.25)
			(net 1 "GND")
			(pintype "passive")
		)
		(pad "2" smd roundrect
			(at 0.32 0.002 315)
			(size 0.46 0.4)
			(layers "B.Cu" "B.Mask")
			(roundrect_rratio 0.25)
			(net 6 "+1V0_MGTAVCC")
			(pintype "passive")
		)
	)
)
